# T6G (Grand Teton) — schematic netlist excerpt (pin names and nets, part order shuffled) for the footprints in the layout excerpt that follows; sources: Cadence DE-HDL packaged netlist, KiCad conversion of 04192023_DAF0TMB3IC0_F0TG_MB_C_brd_V02_OCP.brd

C265  Q_CAP  1UF 4V 20% X6S  pkg 0201  page 323 : A = P0V9_CPU1_RT0_2A ; B = GND
C780  Q_CAP  0.1UF 10V 10% X7S  pkg C0201  page 301 : A = P0V9_CPU0_RT_2D ; B = GND

Q79  MOSFET_NCH_DUAL  PJT138K IC  pkg SOT363XD  page 255
  S1  = GND
  G1  = FM_LED_PWRGD_PVDD33_S5
  D2  = LED_PWRGD_PVDDCR_CPU0_P0_D
  S2  = GND
  G2  = FM_LED_PWRGD_PVDDCR_CPU0_P0
  D1  = LED_PWRGD_PVDD33_S5_D

C6622  Q_CAP_DIFFBUS  DIFF BUS_0.22UF 6.3V 20% X6S  pkg C0201  page 308 : \1\ = P5E_CPU0_P3_TX_BUF_C_DN<12> ; \2\ = P5E_CPU0_P3_TX_BUF_DN<12>

(kicad_pcb
	(version 20260206)
	(generator "pcbnew")
	(generator_version "10.0")
	(general
		(thickness 1.6)
		(legacy_teardrops no)
	)
	(paper "A4")
	(title_block
		(title "04192023_DAF0TMB3IC0_F0TG_MB_C_brd_V02_OCP.brd")
		(comment 1 "Grand Teton / footprints 6512-6515 of 8354")
	)
	(layers
		(0 "F.Cu" signal "TOP")
		(4 "In1.Cu" signal "GND")
		(6 "In2.Cu" signal "IN1")
		(8 "In3.Cu" signal "GND1")
		(10 "In4.Cu" signal "IN2")
		(12 "In5.Cu" signal "GND2")
		(14 "In6.Cu" signal "IN3")
		(16 "In7.Cu" signal "GND3")
		(18 "In8.Cu" signal "VCC")
		(20 "In9.Cu" signal "VCC1")
		(22 "In10.Cu" signal "GND4")
		(24 "In11.Cu" signal "IN4")
		(26 "In12.Cu" signal "GND5")
		(28 "In13.Cu" signal "IN5")
		(30 "In14.Cu" signal "GND6")
		(32 "In15.Cu" signal "IN6")
		(34 "In16.Cu" signal "GND7")
		(2 "B.Cu" signal "BOTTOM")
		(9 "F.Adhes" user "F.Adhesive")
		(11 "B.Adhes" user "B.Adhesive")
		(13 "F.Paste" user "Package Geometry/Pastemask Top")
		(15 "B.Paste" user "Package Geometry/Pastemask Bottom")
		(5 "F.SilkS" user "Ref Des/Silkscreen Top")
		(7 "B.SilkS" user "Ref Des/Silkscreen Bottom")
		(1 "F.Mask" user "Board Geometry/Soldermask Top")
		(3 "B.Mask" user "Board Geometry/Soldermask Bottom")
		(17 "Dwgs.User" user "User.Drawings")
		(19 "Cmts.User" user "User.Comments")
		(21 "Eco1.User" user "User.Eco1")
		(23 "Eco2.User" user "User.Eco2")
		(25 "Edge.Cuts" user "Board Geometry/Outline")
		(27 "Margin" user)
		(31 "F.CrtYd" user "Package Geometry/Place Bound Top")
		(29 "B.CrtYd" user "Package Geometry/Place Bound Bottom")
		(35 "F.Fab" user "Ref Des/Assembly Top")
		(33 "B.Fab" user "Ref Des/Assembly Bottom")
	)
	(footprint ""
		(layer "B.Cu")
		(at 324.336664 -73.534778)
		(property "Reference" "Q79"
			(at 1.4224 -1.768348 0)
			(unlocked yes)
			(layer "B.SilkS")
			(effects
				(font
					(size 0.7874 0.5842)
					(thickness 0.1524)
				)
				(justify left mirror)
			)
		)
		(property "Value" ""
			(at 0 0 0)
			(layer "B.Fab")
			(effects
				(font
					(size 1.27 1.27)
				)
				(justify mirror)
			)
		)
		(duplicate_pad_numbers_are_jumpers no)
		(fp_line
			(start -1.332738 -1.100074)
			(end -1.332738 1.100074)
			(stroke
				(width 0.1524)
				(type default)
			)
			(layer "B.SilkS")
		)
		(fp_line
			(start -1.332738 1.100074)
			(end 1.332738 1.100074)
			(stroke
				(width 0.1524)
				(type default)
			)
			(layer "B.SilkS")
		)
		(fp_line
			(start -0.4826 -1.100074)
			(end -1.332738 -1.100074)
			(stroke
				(width 0.1524)
				(type default)
			)
			(layer "B.SilkS")
		)
		(fp_line
			(start 0 -0.541274)
			(end -0.4826 -1.100074)
			(stroke
				(width 0.1524)
				(type default)
			)
			(layer "B.SilkS")
		)
		(fp_line
			(start 0.4826 -1.100074)
			(end 0 -0.541274)
			(stroke
				(width 0.1524)
				(type default)
			)
			(layer "B.SilkS")
		)
		(fp_line
			(start 1.332738 -1.100074)
			(end 0.4826 -1.100074)
			(stroke
				(width 0.1524)
				(type default)
			)
			(layer "B.SilkS")
		)
		(fp_line
			(start 1.332738 1.100074)
			(end 1.332738 -1.100074)
			(stroke
				(width 0.1524)
				(type default)
			)
			(layer "B.SilkS")
		)
		(fp_poly
			(pts
				(xy 1.334516 -0.649986) (xy 2.036572 -1.001014) (xy 2.036572 -0.298958)
			)
			(stroke
				(width 0)
				(type default)
			)
			(fill yes)
			(layer "B.SilkS")
		)
		(fp_line
			(start -0.674878 -1.100074)
			(end -0.674878 1.100074)
			(stroke
				(width 0.1)
				(type default)
			)
			(layer "B.Fab")
		)
		(fp_line
			(start -0.674878 1.100074)
			(end 0.674878 1.100074)
			(stroke
				(width 0.1)
				(type default)
			)
			(layer "B.Fab")
		)
		(fp_line
			(start 0.674878 -1.100074)
			(end -0.674878 -1.100074)
			(stroke
				(width 0.1)
				(type default)
			)
			(layer "B.Fab")
		)
		(fp_line
			(start 0.674878 1.100074)
			(end 0.674878 -1.100074)
			(stroke
				(width 0.1)
				(type default)
			)
			(layer "B.Fab")
		)
		(fp_poly
			(pts
				(xy 2.2352 -0.298958) (xy 2.2352 -1.001014) (xy 1.533144 -0.649986)
			)
			(stroke
				(width 0)
				(type default)
			)
			(fill yes)
			(layer "B.Fab")
		)
		(pad "1" smd rect
			(at 0.94996 -0.649986 90)
			(size 0.4318 0.508)
			(layers "B.Cu" "B.Mask" "B.Paste")
			(net "GND")
		)
		(pad "2" smd rect
			(at 0.94996 0 90)
			(size 0.4318 0.508)
			(layers "B.Cu" "B.Mask" "B.Paste")
			(net "FM_LED_PWRGD_PVDD33_S5")
		)
		(pad "3" smd rect
			(at 0.94996 0.649986 90)
			(size 0.4318 0.508)
			(layers "B.Cu" "B.Mask" "B.Paste")
			(net "LED_PWRGD_PVDDCR_CPU0_P0_D")
		)
		(pad "4" smd rect
			(at -0.94996 0.649986 90)
			(size 0.4318 0.508)
			(layers "B.Cu" "B.Mask" "B.Paste")
			(net "GND")
		)
		(pad "5" smd rect
			(at -0.94996 0 90)
			(size 0.4318 0.508)
			(layers "B.Cu" "B.Mask" "B.Paste")
			(net "FM_LED_PWRGD_PVDDCR_CPU0_P0")
		)
		(pad "6" smd rect
			(at -0.94996 -0.649986 90)
			(size 0.4318 0.508)
			(layers "B.Cu" "B.Mask" "B.Paste")
			(net "LED_PWRGD_PVDD33_S5_D")
		)
	)
	(footprint ""
		(layer "B.Cu")
		(at 50.978562 -386.766562 90)
		(property "Reference" "C265"
			(at 0 0 90)
			(layer "B.SilkS")
			(hide yes)
			(effects
				(font
					(size 1.27 1.27)
				)
				(justify mirror)
			)
		)
		(property "Value" ""
			(at 0 0 90)
			(layer "B.Fab")
			(effects
				(font
					(size 1.27 1.27)
				)
				(justify mirror)
			)
		)
		(duplicate_pad_numbers_are_jumpers no)
		(fp_line
			(start 0.299974 -0.150114)
			(end -0.299974 -0.150114)
			(stroke
				(width 0.1)
				(type default)
			)
			(layer "B.Fab")
		)
		(fp_line
			(start -0.299974 -0.150114)
			(end -0.299974 0.150114)
			(stroke
				(width 0.1)
				(type default)
			)
			(layer "B.Fab")
		)
		(fp_line
			(start 0.299974 0.150114)
			(end 0.299974 -0.150114)
			(stroke
				(width 0.1)
				(type default)
			)
			(layer "B.Fab")
		)
		(fp_line
			(start -0.299974 0.150114)
			(end 0.299974 0.150114)
			(stroke
				(width 0.1)
				(type default)
			)
			(layer "B.Fab")
		)
		(pad "1" smd rect
			(at 0.2667 0 270)
			(size 0.3048 0.381)
			(layers "B.Cu" "B.Mask" "B.Paste")
			(net "P0V9_CPU1_RT0_2A")
		)
		(pad "2" smd rect
			(at -0.2667 0 270)
			(size 0.3048 0.381)
			(layers "B.Cu" "B.Mask" "B.Paste")
			(net "GND")
		)
	)
	(footprint ""
		(layer "B.Cu")
		(at 409.006294 -395.148562 90)
		(property "Reference" "C780"
			(at 0 0 90)
			(layer "B.SilkS")
			(hide yes)
			(effects
				(font
					(size 1.27 1.27)
				)
				(justify mirror)
			)
		)
		(property "Value" ""
			(at 0 0 90)
			(layer "B.Fab")
			(effects
				(font
					(size 1.27 1.27)
				)
				(justify mirror)
			)
		)
		(duplicate_pad_numbers_are_jumpers no)
		(fp_line
			(start 0.299974 -0.150114)
			(end -0.299974 -0.150114)
			(stroke
				(width 0.1)
				(type default)
			)
			(layer "B.Fab")
		)
		(fp_line
			(start -0.299974 -0.150114)
			(end -0.299974 0.150114)
			(stroke
				(width 0.1)
				(type default)
			)
			(layer "B.Fab")
		)
		(fp_line
			(start 0.299974 0.150114)
			(end 0.299974 -0.150114)
			(stroke
				(width 0.1)
				(type default)
			)
			(layer "B.Fab")
		)
		(fp_line
			(start -0.299974 0.150114)
			(end 0.299974 0.150114)
			(stroke
				(width 0.1)
				(type default)
			)
			(layer "B.Fab")
		)
		(pad "1" smd rect
			(at 0.2667 0 270)
			(size 0.3048 0.381)
			(layers "B.Cu" "B.Mask" "B.Paste")
			(net "P0V9_CPU0_RT_2D")
		)
		(pad "2" smd rect
			(at -0.2667 0 270)
			(size 0.3048 0.381)
			(layers "B.Cu" "B.Mask" "B.Paste")
			(net "GND")
		)
	)
	(footprint ""
		(layer "B.Cu")
		(at 409.159202 -416.899344 90)
		(property "Reference" "C6622"
			(at 0 0 90)
			(layer "B.SilkS")
			(hide yes)
			(effects
				(font
					(size 1.27 1.27)
				)
				(justify mirror)
			)
		)
		(property "Value" ""
			(at 0 0 90)
			(layer "B.Fab")
			(effects
				(font
					(size 1.27 1.27)
				)
				(justify mirror)
			)
		)
		(duplicate_pad_numbers_are_jumpers no)
		(fp_line
			(start 0.299974 -0.150114)
			(end -0.299974 -0.150114)
			(stroke
				(width 0.1)
				(type default)
			)
			(layer "B.Fab")
		)
		(fp_line
			(start -0.299974 -0.150114)
			(end -0.299974 0.150114)
			(stroke
				(width 0.1)
				(type default)
			)
			(layer "B.Fab")
		)
		(fp_line
			(start 0.299974 0.150114)
			(end 0.299974 -0.150114)
			(stroke
				(width 0.1)
				(type default)
			)
			(layer "B.Fab")
		)
		(fp_line
			(start -0.299974 0.150114)
			(end 0.299974 0.150114)
			(stroke
				(width 0.1)
				(type default)
			)
			(layer "B.Fab")
		)
		(pad "1" smd rect
			(at 0.2667 0 270)
			(size 0.3048 0.381)
			(layers "B.Cu" "B.Mask" "B.Paste")
			(net "P5E_CPU0_P3_TX_BUF_C_DN<12>")
		)
		(pad "2" smd rect
			(at -0.2667 0 270)
			(size 0.3048 0.381)
			(layers "B.Cu" "B.Mask" "B.Paste")
			(net "P5E_CPU0_P3_TX_BUF_DN<12>")
		)
	)
)
